(kicad_pcb
	(version 20260206)
	(generator "pcbnew")
	(generator_version "10.0")
	(general
		(thickness 1.6)
		(legacy_teardrops no)
	)
	(paper "A4")
	(title_block
		(title "Bryce Canyon_SCC_16316-1_OCP.brd")
		(comment 1 "Bryce Canyon / footprints 207-212 of 1561")
	)
	(layers
		(0 "F.Cu" signal "TOP")
		(4 "In1.Cu" signal "L2GND")
		(6 "In2.Cu" signal "L3")
		(8 "In3.Cu" signal "L4VCC")
		(10 "In4.Cu" signal "L5VCC")
		(12 "In5.Cu" signal "L6")
		(14 "In6.Cu" signal "L7GND")
		(2 "B.Cu" signal "BOTTOM")
		(9 "F.Adhes" user "F.Adhesive")
		(11 "B.Adhes" user "B.Adhesive")
		(13 "F.Paste" user "Package Geometry/Pastemask Top")
		(15 "B.Paste" user "Package Geometry/Pastemask Bottom")
		(5 "F.SilkS" user "Ref Des/Silkscreen Top")
		(7 "B.SilkS" user "Ref Des/Silkscreen Bottom")
		(1 "F.Mask" user "Board Geometry/Soldermask Top")
		(3 "B.Mask" user "Board Geometry/Soldermask Bottom")
		(17 "Dwgs.User" user "User.Drawings")
		(19 "Cmts.User" user "User.Comments")
		(21 "Eco1.User" user "User.Eco1")
		(23 "Eco2.User" user "User.Eco2")
		(25 "Edge.Cuts" user "Board Geometry/Outline")
		(27 "Margin" user)
		(31 "F.CrtYd" user "Package Geometry/Place Bound Top")
		(29 "B.CrtYd" user "Package Geometry/Place Bound Bottom")
		(35 "F.Fab" user "Ref Des/Assembly Top")
		(33 "B.Fab" user "Ref Des/Assembly Bottom")
	)
	(footprint ""
		(layer "F.Cu")
		(at 45.339 -49.784 180)
		(property "Reference" "C672"
			(at 0 0 180)
			(layer "F.SilkS")
			(hide yes)
			(effects
				(font
					(size 1.27 1.27)
				)
			)
		)
		(property "Value" "SCD1U50V3KX-GP"
			(at 0 -2.8194 180)
			(unlocked yes)
			(layer "F.Fab")
			(hide yes)
			(effects
				(font
					(size 1.016 1.016)
					(thickness 0.1524)
				)
			)
		)
		(property "Device Type" "C603H36"
			(at 0 -4.3434 180)
			(unlocked yes)
			(layer "F.Fab")
			(hide yes)
			(effects
				(font
					(size 1.016 1.016)
					(thickness 0.1524)
				)
			)
		)
		(duplicate_pad_numbers_are_jumpers no)
		(fp_line
			(start 0.508 0)
			(end -0.508 0)
			(stroke
				(width 0.2032)
				(type default)
			)
			(layer "F.SilkS")
		)
		(fp_rect
			(start -0.5842 1.3335)
			(end 0.5842 -1.3335)
			(stroke
				(width 0)
				(type default)
			)
			(fill no)
			(layer "F.CrtYd")
		)
		(fp_rect
			(start -0.5842 1.3335)
			(end 0.5842 -1.3335)
			(stroke
				(width 0)
				(type default)
			)
			(fill no)
			(layer "F.Fab")
		)
		(pad "1" smd custom
			(at 0 -0.762 180)
			(size 0.2159 0.2159)
			(layers "F.Cu" "F.Mask" "F.Paste")
			(net "P12V_STBY_VIN_Q7")
			(options
				(clearance outline)
				(anchor circle)
			)
			(primitives
				(gr_poly
					(pts
						(arc
							(start -0.3302 -0.4318)
							(mid -0.402042 -0.402042)
							(end -0.4318 -0.3302)
						)
						(arc
							(start -0.4318 0.3302)
							(mid -0.402042 0.402042)
							(end -0.3302 0.4318)
						)
						(arc
							(start 0.3302 0.4318)
							(mid 0.402042 0.402042)
							(end 0.4318 0.3302)
						)
						(arc
							(start 0.4318 -0.3302)
							(mid 0.402042 -0.402042)
							(end 0.3302 -0.4318)
						)
					)
					(width 0)
					(fill yes)
				)
			)
		)
		(pad "2" smd custom
			(at 0 0.762 180)
			(size 0.2159 0.2159)
			(layers "F.Cu" "F.Mask" "F.Paste")
			(net "GND")
			(options
				(clearance outline)
				(anchor circle)
			)
			(primitives
				(gr_poly
					(pts
						(arc
							(start -0.3302 -0.4318)
							(mid -0.402042 -0.402042)
							(end -0.4318 -0.3302)
						)
						(arc
							(start -0.4318 0.3302)
							(mid -0.402042 0.402042)
							(end -0.3302 0.4318)
						)
						(arc
							(start 0.3302 0.4318)
							(mid 0.402042 0.402042)
							(end 0.4318 0.3302)
						)
						(arc
							(start 0.4318 -0.3302)
							(mid 0.402042 -0.402042)
							(end 0.3302 -0.4318)
						)
					)
					(width 0)
					(fill yes)
				)
			)
		)
	)
	(footprint ""
		(layer "F.Cu")
		(at 81.650586 -76.63053 90)
		(property "Reference" "BLED1"
			(at 0 0 90)
			(layer "F.SilkS")
			(hide yes)
			(effects
				(font
					(size 1.27 1.27)
				)
			)
		)
		(property "Value" "LED-YG-51-GP"
			(at -2.6924 -1.4224 90)
			(unlocked yes)
			(layer "F.Fab")
			(hide yes)
			(effects
				(font
					(size 1.016 1.016)
					(thickness 0.1524)
				)
			)
		)
		(property "Device Type" "LED1608AKH40"
			(at -2.6924 -2.9464 90)
			(unlocked yes)
			(layer "F.Fab")
			(hide yes)
			(effects
				(font
					(size 1.016 1.016)
					(thickness 0.1524)
				)
			)
		)
		(duplicate_pad_numbers_are_jumpers no)
		(fp_line
			(start 0.6604 -1.3716)
			(end 0.6604 1.3716)
			(stroke
				(width 0.1524)
				(type default)
			)
			(layer "F.SilkS")
		)
		(fp_line
			(start -0.6604 -1.3716)
			(end 0.6604 -1.3716)
			(stroke
				(width 0.1524)
				(type default)
			)
			(layer "F.SilkS")
		)
		(fp_line
			(start 0.6604 1.3716)
			(end -0.6604 1.3716)
			(stroke
				(width 0.1524)
				(type default)
			)
			(layer "F.SilkS")
		)
		(fp_line
			(start -0.6604 1.3716)
			(end -0.6604 -1.3716)
			(stroke
				(width 0.1524)
				(type default)
			)
			(layer "F.SilkS")
		)
		(fp_line
			(start -0.5969 1.5494)
			(end 0.5842 1.5494)
			(stroke
				(width 0.508)
				(type default)
			)
			(layer "F.SilkS")
		)
		(fp_line
			(start 0.7493 1.651)
			(end 0.7493 1.1811)
			(stroke
				(width 0.3302)
				(type default)
			)
			(layer "F.SilkS")
		)
		(fp_line
			(start -0.7493 1.651)
			(end -0.7493 1.1811)
			(stroke
				(width 0.3302)
				(type default)
			)
			(layer "F.SilkS")
		)
		(fp_rect
			(start -0.6223 1.3335)
			(end 0.6223 -1.3335)
			(stroke
				(width 0)
				(type default)
			)
			(fill no)
			(layer "F.CrtYd")
		)
		(fp_rect
			(start -0.6223 1.3335)
			(end 0.6223 -1.3335)
			(stroke
				(width 0)
				(type default)
			)
			(fill no)
			(layer "F.Fab")
		)
		(pad "A" smd custom
			(at 0 -0.762 90)
			(size 0.2159 0.2159)
			(layers "F.Cu" "F.Mask" "F.Paste")
			(net "EXP_HW_LED_R")
			(options
				(clearance outline)
				(anchor circle)
			)
			(primitives
				(gr_poly
					(pts
						(arc
							(start -0.3302 -0.4318)
							(mid -0.402042 -0.402042)
							(end -0.4318 -0.3302)
						)
						(arc
							(start -0.4318 0.3302)
							(mid -0.402042 0.402042)
							(end -0.3302 0.4318)
						)
						(arc
							(start 0.3302 0.4318)
							(mid 0.402042 0.402042)
							(end 0.4318 0.3302)
						)
						(arc
							(start 0.4318 -0.3302)
							(mid 0.402042 -0.402042)
							(end 0.3302 -0.4318)
						)
					)
					(width 0)
					(fill yes)
				)
			)
		)
		(pad "K" smd custom
			(at 0 0.762 90)
			(size 0.2159 0.2159)
			(layers "F.Cu" "F.Mask" "F.Paste")
			(net "EXP_HW_LED_D")
			(options
				(clearance outline)
				(anchor circle)
			)
			(primitives
				(gr_poly
					(pts
						(arc
							(start -0.3302 -0.4318)
							(mid -0.402042 -0.402042)
							(end -0.4318 -0.3302)
						)
						(arc
							(start -0.4318 0.3302)
							(mid -0.402042 0.402042)
							(end -0.3302 0.4318)
						)
						(arc
							(start 0.3302 0.4318)
							(mid 0.402042 0.402042)
							(end 0.4318 0.3302)
						)
						(arc
							(start 0.4318 -0.3302)
							(mid 0.402042 -0.402042)
							(end 0.3302 -0.4318)
						)
					)
					(width 0)
					(fill yes)
				)
			)
		)
	)
	(footprint ""
		(layer "F.Cu")
		(at 196.369432 -77.457554 90)
		(property "Reference" "U30"
			(at 0 0 90)
			(layer "F.SilkS")
			(hide yes)
			(effects
				(font
					(size 1.27 1.27)
				)
			)
		)
		(property "Value" "TMP75AIDGKR-GP"
			(at -0.1143 -9.1948 90)
			(unlocked yes)
			(layer "F.Fab")
			(hide yes)
			(effects
				(font
					(size 1.016 1.016)
					(thickness 0.1524)
				)
			)
		)
		(property "Device Type" "MSOP8-1H44"
			(at -0.1143 -10.795 90)
			(unlocked yes)
			(layer "F.Fab")
			(hide yes)
			(effects
				(font
					(size 1.016 1.016)
					(thickness 0.1524)
				)
			)
		)
		(duplicate_pad_numbers_are_jumpers no)
		(fp_line
			(start 1.0795 -1.016)
			(end -1.9558 -1.016)
			(stroke
				(width 0.1524)
				(type default)
			)
			(layer "F.SilkS")
		)
		(fp_line
			(start -1.9558 -1.016)
			(end -1.9558 1.016)
			(stroke
				(width 0.1524)
				(type default)
			)
			(layer "F.SilkS")
		)
		(fp_line
			(start -1.9558 -0.5461)
			(end -1.4478 -0.0381)
			(stroke
				(width 0.1524)
				(type default)
			)
			(layer "F.SilkS")
		)
		(fp_line
			(start -1.4478 -0.0381)
			(end -1.9558 0.4699)
			(stroke
				(width 0.1524)
				(type default)
			)
			(layer "F.SilkS")
		)
		(fp_line
			(start 1.0795 1.016)
			(end 1.0795 -1.016)
			(stroke
				(width 0.1524)
				(type default)
			)
			(layer "F.SilkS")
		)
		(fp_line
			(start -1.9558 1.016)
			(end 1.0795 1.016)
			(stroke
				(width 0.1524)
				(type default)
			)
			(layer "F.SilkS")
		)
		(fp_line
			(start -1.778 1.0922)
			(end -1.778 3.048)
			(stroke
				(width 0.508)
				(type default)
			)
			(layer "F.SilkS")
		)
		(fp_poly
			(pts
				(xy -1.1557 -1.016) (xy -1.1557 1.016) (xy 1.1557 1.016) (xy 1.1557 -1.016)
			)
			(stroke
				(width 0)
				(type default)
			)
			(fill yes)
			(layer "F.SilkS")
		)
		(fp_rect
			(start -1.4986 2.4511)
			(end 1.4986 -2.4511)
			(stroke
				(width 0)
				(type default)
			)
			(fill no)
			(layer "F.CrtYd")
		)
		(fp_poly
			(pts
				(xy -2.032 3.302) (xy -2.032 -3.302) (xy 2.032 -3.302) (xy 2.032 -2.1209) (xy 1.4986 -2.1209) (xy 1.4986 -2.4511)
				(xy -1.4986 -2.4511) (xy -1.4986 2.4511) (xy 1.4986 2.4511) (xy 1.4986 -2.1082) (xy 2.032 -2.1082)
				(xy 2.032 3.302)
			)
			(stroke
				(width 0)
				(type default)
			)
			(fill no)
			(layer "F.CrtYd")
		)
		(fp_rect
			(start -2.032 3.302)
			(end 2.032 -3.302)
			(stroke
				(width 0)
				(type default)
			)
			(fill no)
			(layer "F.Fab")
		)
		(pad "1" smd rect
			(at -0.97536 2.05486 90)
			(size 0.3556 1.524)
			(layers "F.Cu" "F.Mask" "F.Paste")
			(net "TEMP2_SDA")
		)
		(pad "2" smd rect
			(at -0.32512 2.05486 90)
			(size 0.3556 1.524)
			(layers "F.Cu" "F.Mask" "F.Paste")
			(net "TEMP2_SCL")
		)
		(pad "3" smd rect
			(at 0.32512 2.05486 90)
			(size 0.3556 1.524)
			(layers "F.Cu" "F.Mask" "F.Paste")
			(net "TEMP2_ALERT")
		)
		(pad "4" smd rect
			(at 0.97536 2.05486 90)
			(size 0.3556 1.524)
			(layers "F.Cu" "F.Mask" "F.Paste")
			(net "GND")
		)
		(pad "5" smd rect
			(at 0.97536 -2.05486 90)
			(size 0.3556 1.524)
			(layers "F.Cu" "F.Mask" "F.Paste")
			(net "TEMP2_A2")
		)
		(pad "6" smd rect
			(at 0.32512 -2.05486 90)
			(size 0.3556 1.524)
			(layers "F.Cu" "F.Mask" "F.Paste")
			(net "TEMP2_A1")
		)
		(pad "7" smd rect
			(at -0.32512 -2.05486 90)
			(size 0.3556 1.524)
			(layers "F.Cu" "F.Mask" "F.Paste")
			(net "TEMP2_A0")
		)
		(pad "8" smd rect
			(at -0.97536 -2.05486 90)
			(size 0.3556 1.524)
			(layers "F.Cu" "F.Mask" "F.Paste")
			(net "P3V3")
		)
	)
	(footprint ""
		(layer "F.Cu")
		(at 179.35448 -110.80242)
		(property "Reference" "R603"
			(at 0 0 0)
			(layer "F.SilkS")
			(hide yes)
			(effects
				(font
					(size 1.27 1.27)
				)
			)
		)
		(property "Value" "0R2J-2-GP"
			(at 0.064008 -3.993896 0)
			(unlocked yes)
			(layer "F.Fab")
			(hide yes)
			(effects
				(font
					(size 1.016 1.016)
					(thickness 0.1524)
				)
			)
		)
		(property "Device Type" "R402H16"
			(at 0.064008 -5.517896 0)
			(unlocked yes)
			(layer "F.Fab")
			(hide yes)
			(effects
				(font
					(size 1.016 1.016)
					(thickness 0.1524)
				)
			)
		)
		(duplicate_pad_numbers_are_jumpers no)
		(fp_line
			(start -0.508 -0.9398)
			(end -0.508 0.9398)
			(stroke
				(width 0.1524)
				(type default)
			)
			(layer "F.SilkS")
		)
		(fp_line
			(start 0.508 -0.9398)
			(end -0.508 -0.9398)
			(stroke
				(width 0.1524)
				(type default)
			)
			(layer "F.SilkS")
		)
		(fp_rect
			(start -0.508 0.9398)
			(end 0.508 -0.9398)
			(stroke
				(width 0)
				(type default)
			)
			(fill no)
			(layer "F.CrtYd")
		)
		(fp_rect
			(start -0.508 0.9398)
			(end 0.508 -0.9398)
			(stroke
				(width 0)
				(type default)
			)
			(fill no)
			(layer "F.Fab")
		)
		(pad "1" smd custom
			(at 0 -0.4445)
			(size 0.1397 0.1397)
			(layers "F.Cu" "F.Mask" "F.Paste")
			(net "P1V8_C_PG")
			(options
				(clearance outline)
				(anchor circle)
			)
			(primitives
				(gr_poly
					(pts
						(arc
							(start -0.1778 -0.2794)
							(mid -0.249642 -0.249642)
							(end -0.2794 -0.1778)
						)
						(arc
							(start -0.2794 0.1778)
							(mid -0.249642 0.249642)
							(end -0.1778 0.2794)
						)
						(arc
							(start 0.1778 0.2794)
							(mid 0.249642 0.249642)
							(end 0.2794 0.1778)
						)
						(arc
							(start 0.2794 -0.1778)
							(mid 0.249642 -0.249642)
							(end 0.1778 -0.2794)
						)
					)
					(width 0)
					(fill yes)
				)
			)
		)
		(pad "2" smd custom
			(at 0 0.4445)
			(size 0.1397 0.1397)
			(layers "F.Cu" "F.Mask" "F.Paste")
			(net "P1V8_C_PG_R_1")
			(options
				(clearance outline)
				(anchor circle)
			)
			(primitives
				(gr_poly
					(pts
						(arc
							(start -0.1778 -0.2794)
							(mid -0.249642 -0.249642)
							(end -0.2794 -0.1778)
						)
						(arc
							(start -0.2794 0.1778)
							(mid -0.249642 0.249642)
							(end -0.1778 0.2794)
						)
						(arc
							(start 0.1778 0.2794)
							(mid 0.249642 0.249642)
							(end 0.2794 0.1778)
						)
						(arc
							(start 0.2794 -0.1778)
							(mid 0.249642 -0.249642)
							(end 0.1778 -0.2794)
						)
					)
					(width 0)
					(fill yes)
				)
			)
		)
	)
	(footprint ""
		(layer "F.Cu")
		(at 144.54378 -117.66042 180)
		(property "Reference" "C675"
			(at 0 0 180)
			(layer "F.SilkS")
			(hide yes)
			(effects
				(font
					(size 1.27 1.27)
				)
			)
		)
		(property "Value" "SCD1U50V3KX-GP"
			(at 0 -2.8194 180)
			(unlocked yes)
			(layer "F.Fab")
			(hide yes)
			(effects
				(font
					(size 1.016 1.016)
					(thickness 0.1524)
				)
			)
		)
		(property "Device Type" "C603H36"
			(at 0 -4.3434 180)
			(unlocked yes)
			(layer "F.Fab")
			(hide yes)
			(effects
				(font
					(size 1.016 1.016)
					(thickness 0.1524)
				)
			)
		)
		(duplicate_pad_numbers_are_jumpers no)
		(fp_line
			(start 0.508 0)
			(end -0.508 0)
			(stroke
				(width 0.2032)
				(type default)
			)
			(layer "F.SilkS")
		)
		(fp_rect
			(start -0.5842 1.3335)
			(end 0.5842 -1.3335)
			(stroke
				(width 0)
				(type default)
			)
			(fill no)
			(layer "F.CrtYd")
		)
		(fp_rect
			(start -0.5842 1.3335)
			(end 0.5842 -1.3335)
			(stroke
				(width 0)
				(type default)
			)
			(fill no)
			(layer "F.Fab")
		)
		(pad "1" smd custom
			(at 0 -0.762 180)
			(size 0.2159 0.2159)
			(layers "F.Cu" "F.Mask" "F.Paste")
			(net "P1V5_E_OUT")
			(options
				(clearance outline)
				(anchor circle)
			)
			(primitives
				(gr_poly
					(pts
						(arc
							(start -0.3302 -0.4318)
							(mid -0.402042 -0.402042)
							(end -0.4318 -0.3302)
						)
						(arc
							(start -0.4318 0.3302)
							(mid -0.402042 0.402042)
							(end -0.3302 0.4318)
						)
						(arc
							(start 0.3302 0.4318)
							(mid 0.402042 0.402042)
							(end 0.4318 0.3302)
						)
						(arc
							(start 0.4318 -0.3302)
							(mid 0.402042 -0.402042)
							(end 0.3302 -0.4318)
						)
					)
					(width 0)
					(fill yes)
				)
			)
		)
		(pad "2" smd custom
			(at 0 0.762 180)
			(size 0.2159 0.2159)
			(layers "F.Cu" "F.Mask" "F.Paste")
			(net "P1V5_E_LL_R")
			(options
				(clearance outline)
				(anchor circle)
			)
			(primitives
				(gr_poly
					(pts
						(arc
							(start -0.3302 -0.4318)
							(mid -0.402042 -0.402042)
							(end -0.4318 -0.3302)
						)
						(arc
							(start -0.4318 0.3302)
							(mid -0.402042 0.402042)
							(end -0.3302 0.4318)
						)
						(arc
							(start 0.3302 0.4318)
							(mid 0.402042 0.402042)
							(end 0.4318 0.3302)
						)
						(arc
							(start 0.4318 -0.3302)
							(mid 0.402042 -0.402042)
							(end 0.3302 -0.4318)
						)
					)
					(width 0)
					(fill yes)
				)
			)
		)
	)
	(footprint ""
		(layer "F.Cu")
		(at 82.2706 -63.373)
		(property "Reference" "R76"
			(at 0 0 0)
			(layer "F.SilkS")
			(hide yes)
			(effects
				(font
					(size 1.27 1.27)
				)
			)
		)
		(property "Value" "0R2J-2-GP"
			(at 0.064008 -3.993896 0)
			(unlocked yes)
			(layer "F.Fab")
			(hide yes)
			(effects
				(font
					(size 1.016 1.016)
					(thickness 0.1524)
				)
			)
		)
		(property "Device Type" "R402H16"
			(at 0.064008 -5.517896 0)
			(unlocked yes)
			(layer "F.Fab")
			(hide yes)
			(effects
				(font
					(size 1.016 1.016)
					(thickness 0.1524)
				)
			)
		)
		(duplicate_pad_numbers_are_jumpers no)
		(fp_line
			(start -0.508 -0.9398)
			(end -0.508 0.9398)
			(stroke
				(width 0.1524)
				(type default)
			)
			(layer "F.SilkS")
		)
		(fp_line
			(start 0.508 -0.9398)
			(end -0.508 -0.9398)
			(stroke
				(width 0.1524)
				(type default)
			)
			(layer "F.SilkS")
		)
		(fp_rect
			(start -0.508 0.9398)
			(end 0.508 -0.9398)
			(stroke
				(width 0)
				(type default)
			)
			(fill no)
			(layer "F.CrtYd")
		)
		(fp_rect
			(start -0.508 0.9398)
			(end 0.508 -0.9398)
			(stroke
				(width 0)
				(type default)
			)
			(fill no)
			(layer "F.Fab")
		)
		(pad "1" smd custom
			(at 0 -0.4445)
			(size 0.1397 0.1397)
			(layers "F.Cu" "F.Mask" "F.Paste")
			(net "LS_EN_U24")
			(options
				(clearance outline)
				(anchor circle)
			)
			(primitives
				(gr_poly
					(pts
						(arc
							(start -0.1778 -0.2794)
							(mid -0.249642 -0.249642)
							(end -0.2794 -0.1778)
						)
						(arc
							(start -0.2794 0.1778)
							(mid -0.249642 0.249642)
							(end -0.1778 0.2794)
						)
						(arc
							(start 0.1778 0.2794)
							(mid 0.249642 0.249642)
							(end 0.2794 0.1778)
						)
						(arc
							(start 0.2794 -0.1778)
							(mid 0.249642 -0.249642)
							(end 0.1778 -0.2794)
						)
					)
					(width 0)
					(fill yes)
				)
			)
		)
		(pad "2" smd custom
			(at 0 0.4445)
			(size 0.1397 0.1397)
			(layers "F.Cu" "F.Mask" "F.Paste")
			(net "LS_EN_N")
			(options
				(clearance outline)
				(anchor circle)
			)
			(primitives
				(gr_poly
					(pts
						(arc
							(start -0.1778 -0.2794)
							(mid -0.249642 -0.249642)
							(end -0.2794 -0.1778)
						)
						(arc
							(start -0.2794 0.1778)
							(mid -0.249642 0.249642)
							(end -0.1778 0.2794)
						)
						(arc
							(start 0.1778 0.2794)
							(mid 0.249642 0.249642)
							(end 0.2794 0.1778)
						)
						(arc
							(start 0.2794 -0.1778)
							(mid 0.249642 -0.249642)
							(end 0.1778 -0.2794)
						)
					)
					(width 0)
					(fill yes)
				)
			)
		)
	)
)
